(kicad_pcb
	(version 20241229)
	(generator "pcbnew")
	(generator_version "9.0")
	(general
		(thickness 1.711)
		(legacy_teardrops no)
	)
	(paper "A4")
	(title_block
		(title "Antmicro Baseboard for Jetson AGX Thor")
		(date "2026-02-18")
		(rev "1.1.0")
		(company "Antmicro Ltd")
		(comment 1 "www.antmicro.com")
		(comment 9 "footprints 484-485 of 1170")
	)
	(layers
		(0 "F.Cu" signal)
		(4 "In1.Cu" signal)
		(6 "In2.Cu" signal)
		(8 "In3.Cu" signal)
		(10 "In4.Cu" jumper)
		(12 "In5.Cu" signal)
		(14 "In6.Cu" signal)
		(16 "In7.Cu" signal)
		(18 "In8.Cu" signal)
		(2 "B.Cu" signal)
		(9 "F.Adhes" user "F.Adhesive")
		(11 "B.Adhes" user "B.Adhesive")
		(13 "F.Paste" user)
		(15 "B.Paste" user)
		(5 "F.SilkS" user "F.Silkscreen")
		(7 "B.SilkS" user "B.Silkscreen")
		(1 "F.Mask" user)
		(3 "B.Mask" user)
		(17 "Dwgs.User" user "User.Drawings")
		(19 "Cmts.User" user "User.Comments")
		(21 "Eco1.User" user "User.Eco1")
		(23 "Eco2.User" user "User.Eco2")
		(25 "Edge.Cuts" user)
		(27 "Margin" user)
		(31 "F.CrtYd" user "F.Courtyard")
		(29 "B.CrtYd" user "B.Courtyard")
		(35 "F.Fab" user)
		(33 "B.Fab" user)
	)
	(footprint "antmicro-footprints:C_0805_2012Metric"
		(layer "F.Cu")
		(at 167.72 99.81 90)
		(descr "Capacitor SMD 0805")
		(tags "capacitor SMD 0805")
		(property "Reference" "C250"
			(at -4.595 0.345 90)
			(layer "F.SilkS")
			(effects
				(font
					(size 0.7 0.7)
					(thickness 0.15)
				)
				(justify left bottom)
			)
		)
		(property "Value" "C_22u_25V_0805"
			(at -2.055717 1.963152 90)
			(layer "F.Fab")
			(effects
				(font
					(size 0.7 0.7)
					(thickness 0.15)
				)
				(justify left bottom)
			)
		)
		(property "Datasheet" "https://product.samsungsem.com/mlcc/CL21A226MAYNNN.do"
			(at 0 0 90)
			(layer "F.Fab")
			(hide yes)
			(effects
				(font
					(size 1.27 1.27)
					(thickness 0.15)
				)
			)
		)
		(property "Description" "SMT Multilayer Ceramic Capacitor, 22uF, +/-20%, 25V, X5R, 0805 [2012 Metric]"
			(at 0 0 90)
			(layer "F.Fab")
			(hide yes)
			(effects
				(font
					(size 1.27 1.27)
					(thickness 0.15)
				)
			)
		)
		(property "MPN" "CL21A226MAYNNNE"
			(at 0 0 90)
			(unlocked yes)
			(layer "F.Fab")
			(hide yes)
			(effects
				(font
					(size 1 1)
					(thickness 0.15)
				)
			)
		)
		(property "Manufacturer" "Samsung Electro-Mechanics"
			(at 0 0 90)
			(unlocked yes)
			(layer "F.Fab")
			(hide yes)
			(effects
				(font
					(size 1 1)
					(thickness 0.15)
				)
			)
		)
		(property "License" "Apache-2.0"
			(at 0 0 90)
			(unlocked yes)
			(layer "F.Fab")
			(hide yes)
			(effects
				(font
					(size 1 1)
					(thickness 0.15)
				)
			)
		)
		(property "Author" "Antmicro"
			(at 0 0 90)
			(unlocked yes)
			(layer "F.Fab")
			(hide yes)
			(effects
				(font
					(size 1 1)
					(thickness 0.15)
				)
			)
		)
		(property "Val" "22u"
			(at 0 0 90)
			(unlocked yes)
			(layer "F.Fab")
			(hide yes)
			(effects
				(font
					(size 1 1)
					(thickness 0.15)
				)
			)
		)
		(property "Voltage" "25V"
			(at 0 0 90)
			(unlocked yes)
			(layer "F.Fab")
			(hide yes)
			(effects
				(font
					(size 1 1)
					(thickness 0.15)
				)
			)
		)
		(property "Dielectric" "X5R"
			(at 0 0 90)
			(unlocked yes)
			(layer "F.Fab")
			(hide yes)
			(effects
				(font
					(size 1 1)
					(thickness 0.15)
				)
			)
		)
		(property "Public" "False"
			(at 0 0 90)
			(unlocked yes)
			(layer "F.Fab")
			(hide yes)
			(effects
				(font
					(size 1 1)
					(thickness 0.15)
				)
			)
		)
		(component_classes
			(class "DCDC_SOM")
		)
		(sheetname "/DCDC/")
		(sheetfile "dcdc.kicad_sch")
		(attr smd)
		(fp_line
			(start -0.3 -0.7)
			(end 0.3 -0.7)
			(stroke
				(width 0.15)
				(type solid)
			)
			(layer "F.SilkS")
		)
		(fp_line
			(start -0.3 0.7)
			(end 0.3 0.7)
			(stroke
				(width 0.15)
				(type solid)
			)
			(layer "F.SilkS")
		)
		(fp_rect
			(start 1.95 -0.9)
			(end -1.95 0.9)
			(stroke
				(width 0.05)
				(type default)
			)
			(fill no)
			(layer "F.CrtYd")
		)
		(fp_rect
			(start -0.95 -0.675)
			(end 0.95 0.675)
			(stroke
				(width 0.15)
				(type solid)
			)
			(fill no)
			(layer "F.Fab")
		)
		(fp_text user "Author: Antmicro"
			(at -1.9 5.947 90)
			(layer "F.Fab")
			(effects
				(font
					(size 0.7 0.7)
					(thickness 0.15)
				)
				(justify left bottom)
			)
		)
		(fp_text user "License: Apache-2.0"
			(at -1.9 4.947 90)
			(layer "F.Fab")
			(effects
				(font
					(size 0.7 0.7)
					(thickness 0.15)
				)
				(justify left bottom)
			)
		)
		(fp_text user "${REFERENCE}"
			(at -1.9 3.947 90)
			(layer "F.Fab")
			(effects
				(font
					(size 0.7 0.7)
					(thickness 0.15)
				)
				(justify left bottom)
			)
		)
		(pad "1" smd roundrect
			(at -1.1 0 90)
			(size 1.2 1.3)
			(layers "F.Cu" "F.Mask" "F.Paste")
			(roundrect_rratio 0.25)
			(net 1 "GND")
			(pintype "passive")
		)
		(pad "2" smd roundrect
			(at 1.1 0 90)
			(size 1.2 1.3)
			(layers "F.Cu" "F.Mask" "F.Paste")
			(roundrect_rratio 0.25)
			(net 903 "/DCDC/16V_OUT")
			(pintype "passive")
		)
	)
	(footprint "antmicro-footprints:R_0402_1005Metric"
		(layer "F.Cu")
		(at 88 58.5)
		(descr "Resistor SMD 0402")
		(tags "resistor SMD 0402")
		(property "Reference" "R304"
			(at -19.15 9.55 0)
			(layer "F.SilkS")
			(effects
				(font
					(size 0.7 0.7)
					(thickness 0.15)
				)
				(justify left bottom)
			)
		)
		(property "Value" "R_10k_0402"
			(at -1.011843 1.772046 0)
			(layer "F.Fab")
			(effects
				(font
					(size 0.7 0.7)
					(thickness 0.15)
				)
				(justify left bottom)
			)
		)
		(property "Datasheet" "https://www.bourns.com/docs/product-datasheets/cr.pdf"
			(at 0 0 0)
			(layer "F.Fab")
			(hide yes)
			(effects
				(font
					(size 1.27 1.27)
					(thickness 0.15)
				)
			)
		)
		(property "Description" "SMD Chip Resistor, 10 kohm, ± 1%, 62.5 mW, 0402 [1005 Metric], Thick Film, General Purpose"
			(at 0 0 0)
			(layer "F.Fab")
			(hide yes)
			(effects
				(font
					(size 1.27 1.27)
					(thickness 0.15)
				)
			)
		)
		(property "MPN" "CR0402-FX-1002GLF"
			(at 0 0 0)
			(unlocked yes)
			(layer "F.Fab")
			(hide yes)
			(effects
				(font
					(size 1 1)
					(thickness 0.15)
				)
			)
		)
		(property "Manufacturer" "Bourns"
			(at 0 0 0)
			(unlocked yes)
			(layer "F.Fab")
			(hide yes)
			(effects
				(font
					(size 1 1)
					(thickness 0.15)
				)
			)
		)
		(property "License" "Apache-2.0"
			(at 0 0 0)
			(unlocked yes)
			(layer "F.Fab")
			(hide yes)
			(effects
				(font
					(size 1 1)
					(thickness 0.15)
				)
			)
		)
		(property "Author" "Antmicro"
			(at 0 0 0)
			(unlocked yes)
			(layer "F.Fab")
			(hide yes)
			(effects
				(font
					(size 1 1)
					(thickness 0.15)
				)
			)
		)
		(property "Val" "10k"
			(at 0 0 0)
			(unlocked yes)
			(layer "F.Fab")
			(hide yes)
			(effects
				(font
					(size 1 1)
					(thickness 0.15)
				)
			)
		)
		(property "Tolerance" "1%"
			(at 0 0 0)
			(unlocked yes)
			(layer "F.Fab")
			(hide yes)
			(effects
				(font
					(size 1 1)
					(thickness 0.15)
				)
			)
		)
		(sheetname "/SoM_Power/")
		(sheetfile "som_power.kicad_sch")
		(attr smd)
		(fp_poly
			(pts
				(xy -0.925 -0.47) (xy -0.925 0.47) (xy 0.925 0.47) (xy 0.925 -0.47)
			)
			(stroke
				(width 0.05)
				(type default)
			)
			(fill no)
			(layer "F.CrtYd")
		)
		(fp_poly
			(pts
				(xy -0.5 -0.25) (xy -0.5 0.25) (xy 0.5 0.25) (xy 0.5 -0.25)
			)
			(stroke
				(width 0.15)
				(type solid)
			)
			(fill no)
			(layer "F.Fab")
		)
		(fp_text user "Author: Antmicro"
			(at -0.95 4.169 0)
			(layer "F.Fab")
			(effects
				(font
					(size 0.7 0.7)
					(thickness 0.15)
				)
				(justify left bottom)
			)
		)
		(fp_text user "${REFERENCE}"
			(at -0.95 3.168 0)
			(layer "F.Fab")
			(effects
				(font
					(size 0.7 0.7)
					(thickness 0.15)
				)
				(justify left bottom)
			)
		)
		(fp_text user "License: Apache-2.0"
			(at -0.949999 5.169 0)
			(layer "F.Fab")
			(effects
				(font
					(size 0.7 0.7)
					(thickness 0.15)
				)
				(justify left bottom)
			)
		)
		(pad "1" smd roundrect
			(at -0.48 0)
			(size 0.59 0.64)
			(layers "F.Cu" "F.Mask" "F.Paste")
			(roundrect_rratio 0.25)
			(net 1382 "Net-(R300-Pad2)")
			(pintype "passive")
		)
		(pad "2" smd roundrect
			(at 0.48 0)
			(size 0.59 0.64)
			(layers "F.Cu" "F.Mask" "F.Paste")
			(roundrect_rratio 0.25)
			(net 4 "+3V3_AON")
			(pintype "passive")
		)
	)
)
